(kicad_pcb
	(version 20260206)
	(generator "pcbnew")
	(generator_version "10.0")
	(general
		(thickness 1.6)
		(legacy_teardrops no)
	)
	(paper "A4")
	(title_block
		(title "01162023_DA0F0TEBIF0_F0T_Expander_BD_F_brd_V02_OCP.brd")
		(comment 1 "Grand Teton / footprints 3505-3512 of 9728")
	)
	(layers
		(0 "F.Cu" signal "TOP")
		(4 "In1.Cu" signal "GND")
		(6 "In2.Cu" signal "VCC")
		(8 "In3.Cu" signal "VCC1")
		(10 "In4.Cu" signal "GND1")
		(12 "In5.Cu" signal "IN1")
		(14 "In6.Cu" signal "GND2")
		(16 "In7.Cu" signal "IN2")
		(18 "In8.Cu" signal "GND3")
		(20 "In9.Cu" signal "IN3")
		(22 "In10.Cu" signal "GND4")
		(24 "In11.Cu" signal "IN4")
		(26 "In12.Cu" signal "GND5")
		(28 "In13.Cu" signal "IN5")
		(30 "In14.Cu" signal "GND6")
		(32 "In15.Cu" signal "IN6")
		(34 "In16.Cu" signal "GND7")
		(2 "B.Cu" signal "BOTTOM")
		(9 "F.Adhes" user "F.Adhesive")
		(11 "B.Adhes" user "B.Adhesive")
		(13 "F.Paste" user "Package Geometry/Pastemask Top")
		(15 "B.Paste" user "Package Geometry/Pastemask Bottom")
		(5 "F.SilkS" user "Ref Des/Silkscreen Top")
		(7 "B.SilkS" user "Ref Des/Silkscreen Bottom")
		(1 "F.Mask" user "Board Geometry/Soldermask Top")
		(3 "B.Mask" user "Board Geometry/Soldermask Bottom")
		(17 "Dwgs.User" user "User.Drawings")
		(19 "Cmts.User" user "User.Comments")
		(21 "Eco1.User" user "User.Eco1")
		(23 "Eco2.User" user "User.Eco2")
		(25 "Edge.Cuts" user "Board Geometry/Outline")
		(27 "Margin" user)
		(31 "F.CrtYd" user "Package Geometry/Place Bound Top")
		(29 "B.CrtYd" user "Package Geometry/Place Bound Bottom")
		(35 "F.Fab" user "Ref Des/Assembly Top")
		(33 "B.Fab" user "Ref Des/Assembly Bottom")
	)
	(footprint ""
		(layer "F.Cu")
		(at 286.654748 -22.961346 90)
		(property "Reference" "R1690"
			(at 0 0 90)
			(layer "F.SilkS")
			(hide yes)
			(effects
				(font
					(size 1.27 1.27)
				)
			)
		)
		(property "Value" ""
			(at 0 0 90)
			(layer "F.Fab")
			(effects
				(font
					(size 1.27 1.27)
				)
			)
		)
		(duplicate_pad_numbers_are_jumpers no)
		(fp_line
			(start 0.7874 -0.4064)
			(end 0.7874 0.4064)
			(stroke
				(width 0.1524)
				(type default)
			)
			(layer "F.SilkS")
		)
		(fp_line
			(start -0.7874 -0.4064)
			(end 0.7874 -0.4064)
			(stroke
				(width 0.1524)
				(type default)
			)
			(layer "F.SilkS")
		)
		(fp_line
			(start 0.7874 0.4064)
			(end -0.7874 0.4064)
			(stroke
				(width 0.1524)
				(type default)
			)
			(layer "F.SilkS")
		)
		(fp_line
			(start -0.7874 0.4064)
			(end -0.7874 -0.4064)
			(stroke
				(width 0.1524)
				(type default)
			)
			(layer "F.SilkS")
		)
		(fp_line
			(start -0.12065 -0.305054)
			(end -0.12065 -0.2794)
			(stroke
				(width 0.1)
				(type default)
			)
			(layer "F.Fab")
		)
		(fp_line
			(start -0.67945 -0.305054)
			(end -0.12065 -0.305054)
			(stroke
				(width 0.1)
				(type default)
			)
			(layer "F.Fab")
		)
		(fp_line
			(start 0.67945 -0.3048)
			(end 0.67945 0.3048)
			(stroke
				(width 0.1)
				(type default)
			)
			(layer "F.Fab")
		)
		(fp_line
			(start 0.12065 -0.3048)
			(end 0.67945 -0.3048)
			(stroke
				(width 0.1)
				(type default)
			)
			(layer "F.Fab")
		)
		(fp_line
			(start 0.12065 -0.2794)
			(end 0.12065 -0.3048)
			(stroke
				(width 0.1)
				(type default)
			)
			(layer "F.Fab")
		)
		(fp_line
			(start -0.12065 -0.2794)
			(end 0.12065 -0.2794)
			(stroke
				(width 0.1)
				(type default)
			)
			(layer "F.Fab")
		)
		(fp_line
			(start 0.120396 0.2794)
			(end -0.12065 0.2794)
			(stroke
				(width 0.1)
				(type default)
			)
			(layer "F.Fab")
		)
		(fp_line
			(start -0.12065 0.2794)
			(end -0.12065 0.3048)
			(stroke
				(width 0.1)
				(type default)
			)
			(layer "F.Fab")
		)
		(fp_line
			(start 0.67945 0.3048)
			(end 0.120396 0.3048)
			(stroke
				(width 0.1)
				(type default)
			)
			(layer "F.Fab")
		)
		(fp_line
			(start 0.120396 0.3048)
			(end 0.120396 0.2794)
			(stroke
				(width 0.1)
				(type default)
			)
			(layer "F.Fab")
		)
		(fp_line
			(start -0.12065 0.3048)
			(end -0.67945 0.3048)
			(stroke
				(width 0.1)
				(type default)
			)
			(layer "F.Fab")
		)
		(fp_line
			(start -0.67945 0.3048)
			(end -0.67945 -0.305054)
			(stroke
				(width 0.1)
				(type default)
			)
			(layer "F.Fab")
		)
		(pad "1" smd circle
			(at -0.40005 0 90)
			(size 0 0)
			(layers "F.Cu" "F.Mask" "F.Paste")
			(net "SMB_SSD9_ISO_EN")
		)
		(pad "2" smd circle
			(at 0.40005 0 90)
			(size 0 0)
			(layers "F.Cu" "F.Mask" "F.Paste")
			(net "P3V3_AUX")
		)
	)
	(footprint ""
		(layer "F.Cu")
		(at 336.03438 -187.061856 180)
		(property "Reference" "R4737"
			(at 0 0 180)
			(layer "F.SilkS")
			(hide yes)
			(effects
				(font
					(size 1.27 1.27)
				)
			)
		)
		(property "Value" ""
			(at 0 0 180)
			(layer "F.Fab")
			(effects
				(font
					(size 1.27 1.27)
				)
			)
		)
		(duplicate_pad_numbers_are_jumpers no)
		(fp_line
			(start 0.7874 0.4064)
			(end -0.7874 0.4064)
			(stroke
				(width 0.1524)
				(type default)
			)
			(layer "F.SilkS")
		)
		(fp_line
			(start 0.7874 -0.4064)
			(end 0.7874 0.4064)
			(stroke
				(width 0.1524)
				(type default)
			)
			(layer "F.SilkS")
		)
		(fp_line
			(start -0.7874 0.4064)
			(end -0.7874 -0.4064)
			(stroke
				(width 0.1524)
				(type default)
			)
			(layer "F.SilkS")
		)
		(fp_line
			(start -0.7874 -0.4064)
			(end 0.7874 -0.4064)
			(stroke
				(width 0.1524)
				(type default)
			)
			(layer "F.SilkS")
		)
		(fp_line
			(start 0.67945 0.3048)
			(end 0.120396 0.3048)
			(stroke
				(width 0.1)
				(type default)
			)
			(layer "F.Fab")
		)
		(fp_line
			(start 0.67945 -0.3048)
			(end 0.67945 0.3048)
			(stroke
				(width 0.1)
				(type default)
			)
			(layer "F.Fab")
		)
		(fp_line
			(start 0.12065 -0.2794)
			(end 0.12065 -0.3048)
			(stroke
				(width 0.1)
				(type default)
			)
			(layer "F.Fab")
		)
		(fp_line
			(start 0.12065 -0.3048)
			(end 0.67945 -0.3048)
			(stroke
				(width 0.1)
				(type default)
			)
			(layer "F.Fab")
		)
		(fp_line
			(start 0.120396 0.3048)
			(end 0.120396 0.2794)
			(stroke
				(width 0.1)
				(type default)
			)
			(layer "F.Fab")
		)
		(fp_line
			(start 0.120396 0.2794)
			(end -0.12065 0.2794)
			(stroke
				(width 0.1)
				(type default)
			)
			(layer "F.Fab")
		)
		(fp_line
			(start -0.12065 0.3048)
			(end -0.67945 0.3048)
			(stroke
				(width 0.1)
				(type default)
			)
			(layer "F.Fab")
		)
		(fp_line
			(start -0.12065 0.2794)
			(end -0.12065 0.3048)
			(stroke
				(width 0.1)
				(type default)
			)
			(layer "F.Fab")
		)
		(fp_line
			(start -0.12065 -0.2794)
			(end 0.12065 -0.2794)
			(stroke
				(width 0.1)
				(type default)
			)
			(layer "F.Fab")
		)
		(fp_line
			(start -0.12065 -0.305054)
			(end -0.12065 -0.2794)
			(stroke
				(width 0.1)
				(type default)
			)
			(layer "F.Fab")
		)
		(fp_line
			(start -0.67945 0.3048)
			(end -0.67945 -0.305054)
			(stroke
				(width 0.1)
				(type default)
			)
			(layer "F.Fab")
		)
		(fp_line
			(start -0.67945 -0.305054)
			(end -0.12065 -0.305054)
			(stroke
				(width 0.1)
				(type default)
			)
			(layer "F.Fab")
		)
		(pad "1" smd circle
			(at -0.40005 0 180)
			(size 0 0)
			(layers "F.Cu" "F.Mask" "F.Paste")
			(net "PEX2_PCA9555_INT_R_N")
		)
		(pad "2" smd circle
			(at 0.40005 0 180)
			(size 0 0)
			(layers "F.Cu" "F.Mask" "F.Paste")
			(net "PEX2_PCA9555_INT_N")
		)
	)
	(footprint ""
		(layer "F.Cu")
		(at 38.875208 -356.244906 90)
		(property "Reference" "C2171"
			(at 0 0 90)
			(layer "F.SilkS")
			(hide yes)
			(effects
				(font
					(size 1.27 1.27)
				)
			)
		)
		(property "Value" ""
			(at 0 0 90)
			(layer "F.Fab")
			(effects
				(font
					(size 1.27 1.27)
				)
			)
		)
		(duplicate_pad_numbers_are_jumpers no)
		(fp_line
			(start 0.299974 -0.150114)
			(end 0.299974 0.150114)
			(stroke
				(width 0.1)
				(type default)
			)
			(layer "F.Fab")
		)
		(fp_line
			(start -0.299974 -0.150114)
			(end 0.299974 -0.150114)
			(stroke
				(width 0.1)
				(type default)
			)
			(layer "F.Fab")
		)
		(fp_line
			(start 0.299974 0.150114)
			(end -0.299974 0.150114)
			(stroke
				(width 0.1)
				(type default)
			)
			(layer "F.Fab")
		)
		(fp_line
			(start -0.299974 0.150114)
			(end -0.299974 -0.150114)
			(stroke
				(width 0.1)
				(type default)
			)
			(layer "F.Fab")
		)
		(pad "1" smd rect
			(at -0.2667 0 90)
			(size 0.3048 0.381)
			(layers "F.Cu" "F.Mask" "F.Paste")
			(net "P5E_PEX0_STN4_TX_DN<70>")
		)
		(pad "2" smd rect
			(at 0.2667 0 90)
			(size 0.3048 0.381)
			(layers "F.Cu" "F.Mask" "F.Paste")
			(net "P5E_PEX0_STN4_TX_C_DN<70>")
		)
	)
	(footprint ""
		(layer "F.Cu")
		(at 310.466994 -57.332626)
		(property "Reference" "R6831"
			(at 0 0 0)
			(layer "F.SilkS")
			(hide yes)
			(effects
				(font
					(size 1.27 1.27)
				)
			)
		)
		(property "Value" ""
			(at 0 0 0)
			(layer "F.Fab")
			(effects
				(font
					(size 1.27 1.27)
				)
			)
		)
		(duplicate_pad_numbers_are_jumpers no)
		(fp_line
			(start -0.7874 -0.4064)
			(end 0.7874 -0.4064)
			(stroke
				(width 0.1524)
				(type default)
			)
			(layer "F.SilkS")
		)
		(fp_line
			(start -0.7874 0.4064)
			(end -0.7874 -0.4064)
			(stroke
				(width 0.1524)
				(type default)
			)
			(layer "F.SilkS")
		)
		(fp_line
			(start 0.7874 -0.4064)
			(end 0.7874 0.4064)
			(stroke
				(width 0.1524)
				(type default)
			)
			(layer "F.SilkS")
		)
		(fp_line
			(start 0.7874 0.4064)
			(end -0.7874 0.4064)
			(stroke
				(width 0.1524)
				(type default)
			)
			(layer "F.SilkS")
		)
		(fp_line
			(start -0.67945 -0.305054)
			(end -0.12065 -0.305054)
			(stroke
				(width 0.1)
				(type default)
			)
			(layer "F.Fab")
		)
		(fp_line
			(start -0.67945 0.3048)
			(end -0.67945 -0.305054)
			(stroke
				(width 0.1)
				(type default)
			)
			(layer "F.Fab")
		)
		(fp_line
			(start -0.12065 -0.305054)
			(end -0.12065 -0.2794)
			(stroke
				(width 0.1)
				(type default)
			)
			(layer "F.Fab")
		)
		(fp_line
			(start -0.12065 -0.2794)
			(end 0.12065 -0.2794)
			(stroke
				(width 0.1)
				(type default)
			)
			(layer "F.Fab")
		)
		(fp_line
			(start -0.12065 0.2794)
			(end -0.12065 0.3048)
			(stroke
				(width 0.1)
				(type default)
			)
			(layer "F.Fab")
		)
		(fp_line
			(start -0.12065 0.3048)
			(end -0.67945 0.3048)
			(stroke
				(width 0.1)
				(type default)
			)
			(layer "F.Fab")
		)
		(fp_line
			(start 0.120396 0.2794)
			(end -0.12065 0.2794)
			(stroke
				(width 0.1)
				(type default)
			)
			(layer "F.Fab")
		)
		(fp_line
			(start 0.120396 0.3048)
			(end 0.120396 0.2794)
			(stroke
				(width 0.1)
				(type default)
			)
			(layer "F.Fab")
		)
		(fp_line
			(start 0.12065 -0.3048)
			(end 0.67945 -0.3048)
			(stroke
				(width 0.1)
				(type default)
			)
			(layer "F.Fab")
		)
		(fp_line
			(start 0.12065 -0.2794)
			(end 0.12065 -0.3048)
			(stroke
				(width 0.1)
				(type default)
			)
			(layer "F.Fab")
		)
		(fp_line
			(start 0.67945 -0.3048)
			(end 0.67945 0.3048)
			(stroke
				(width 0.1)
				(type default)
			)
			(layer "F.Fab")
		)
		(fp_line
			(start 0.67945 0.3048)
			(end 0.120396 0.3048)
			(stroke
				(width 0.1)
				(type default)
			)
			(layer "F.Fab")
		)
		(pad "1" smd circle
			(at -0.40005 0)
			(size 0 0)
			(layers "F.Cu" "F.Mask" "F.Paste")
			(net "SSD10_PWR_EN_R")
		)
		(pad "2" smd circle
			(at 0.40005 0)
			(size 0 0)
			(layers "F.Cu" "F.Mask" "F.Paste")
			(net "GND")
		)
	)
	(footprint ""
		(layer "F.Cu")
		(at 59.319922 -20.72005)
		(property "Reference" "H117"
			(at -0.930148 -2.659634 0)
			(unlocked yes)
			(layer "B.SilkS")
			(effects
				(font
					(size 0.7874 0.5842)
					(thickness 0.1524)
				)
				(justify left mirror)
			)
		)
		(property "Value" ""
			(at 0 0 0)
			(layer "F.Fab")
			(effects
				(font
					(size 1.27 1.27)
				)
			)
		)
		(duplicate_pad_numbers_are_jumpers no)
		(pad "1" thru_hole rect
			(at 0 0)
			(size 4.2164 5.0038)
			(drill 2.0066
				(offset 0.099822 0)
			)
			(layers "*.Cu" "*.Mask")
			(remove_unused_layers no)
			(net "Net_8546")
			(clearance -0.8509)
			(padstack
				(mode front_inner_back)
				(layer "Inner"
					(shape circle)
					(size 4.0132 4.0132)
					(clearance -0.7493)
				)
				(layer "B.Cu"
					(shape circle)
					(size 4.0132 4.0132)
					(clearance -0.7493)
				)
			)
		)
	)
	(footprint ""
		(layer "F.Cu")
		(at 338.074 -161.798 180)
		(property "Reference" "R4825"
			(at 0 0 180)
			(layer "F.SilkS")
			(hide yes)
			(effects
				(font
					(size 1.27 1.27)
				)
			)
		)
		(property "Value" ""
			(at 0 0 180)
			(layer "F.Fab")
			(effects
				(font
					(size 1.27 1.27)
				)
			)
		)
		(duplicate_pad_numbers_are_jumpers no)
		(fp_line
			(start 0.7874 0.4064)
			(end -0.7874 0.4064)
			(stroke
				(width 0.1524)
				(type default)
			)
			(layer "F.SilkS")
		)
		(fp_line
			(start 0.7874 -0.4064)
			(end 0.7874 0.4064)
			(stroke
				(width 0.1524)
				(type default)
			)
			(layer "F.SilkS")
		)
		(fp_line
			(start -0.7874 0.4064)
			(end -0.7874 -0.4064)
			(stroke
				(width 0.1524)
				(type default)
			)
			(layer "F.SilkS")
		)
		(fp_line
			(start -0.7874 -0.4064)
			(end 0.7874 -0.4064)
			(stroke
				(width 0.1524)
				(type default)
			)
			(layer "F.SilkS")
		)
		(fp_line
			(start 0.67945 0.3048)
			(end 0.120396 0.3048)
			(stroke
				(width 0.1)
				(type default)
			)
			(layer "F.Fab")
		)
		(fp_line
			(start 0.67945 -0.3048)
			(end 0.67945 0.3048)
			(stroke
				(width 0.1)
				(type default)
			)
			(layer "F.Fab")
		)
		(fp_line
			(start 0.12065 -0.2794)
			(end 0.12065 -0.3048)
			(stroke
				(width 0.1)
				(type default)
			)
			(layer "F.Fab")
		)
		(fp_line
			(start 0.12065 -0.3048)
			(end 0.67945 -0.3048)
			(stroke
				(width 0.1)
				(type default)
			)
			(layer "F.Fab")
		)
		(fp_line
			(start 0.120396 0.3048)
			(end 0.120396 0.2794)
			(stroke
				(width 0.1)
				(type default)
			)
			(layer "F.Fab")
		)
		(fp_line
			(start 0.120396 0.2794)
			(end -0.12065 0.2794)
			(stroke
				(width 0.1)
				(type default)
			)
			(layer "F.Fab")
		)
		(fp_line
			(start -0.12065 0.3048)
			(end -0.67945 0.3048)
			(stroke
				(width 0.1)
				(type default)
			)
			(layer "F.Fab")
		)
		(fp_line
			(start -0.12065 0.2794)
			(end -0.12065 0.3048)
			(stroke
				(width 0.1)
				(type default)
			)
			(layer "F.Fab")
		)
		(fp_line
			(start -0.12065 -0.2794)
			(end 0.12065 -0.2794)
			(stroke
				(width 0.1)
				(type default)
			)
			(layer "F.Fab")
		)
		(fp_line
			(start -0.12065 -0.305054)
			(end -0.12065 -0.2794)
			(stroke
				(width 0.1)
				(type default)
			)
			(layer "F.Fab")
		)
		(fp_line
			(start -0.67945 0.3048)
			(end -0.67945 -0.305054)
			(stroke
				(width 0.1)
				(type default)
			)
			(layer "F.Fab")
		)
		(fp_line
			(start -0.67945 -0.305054)
			(end -0.12065 -0.305054)
			(stroke
				(width 0.1)
				(type default)
			)
			(layer "F.Fab")
		)
		(pad "1" smd circle
			(at -0.40005 0 180)
			(size 0 0)
			(layers "F.Cu" "F.Mask" "F.Paste")
			(net "GND")
		)
		(pad "2" smd circle
			(at 0.40005 0 180)
			(size 0 0)
			(layers "F.Cu" "F.Mask" "F.Paste")
			(net "PCA9555_0_PEX3_A1")
		)
	)
	(footprint ""
		(layer "F.Cu")
		(at 159.93999 -70.52437 90)
		(property "Reference" "PC844"
			(at 0 0 90)
			(layer "F.SilkS")
			(hide yes)
			(effects
				(font
					(size 1.27 1.27)
				)
			)
		)
		(property "Value" ""
			(at 0 0 90)
			(layer "F.Fab")
			(effects
				(font
					(size 1.27 1.27)
				)
			)
		)
		(duplicate_pad_numbers_are_jumpers no)
		(fp_line
			(start 1.524 -0.762)
			(end 1.524 0.762)
			(stroke
				(width 0.1524)
				(type default)
			)
			(layer "F.SilkS")
		)
		(fp_line
			(start -1.524 -0.762)
			(end 1.524 -0.762)
			(stroke
				(width 0.1524)
				(type default)
			)
			(layer "F.SilkS")
		)
		(fp_line
			(start 1.524 0.762)
			(end -1.524 0.762)
			(stroke
				(width 0.1524)
				(type default)
			)
			(layer "F.SilkS")
		)
		(fp_line
			(start -1.524 0.762)
			(end -1.524 -0.762)
			(stroke
				(width 0.1524)
				(type default)
			)
			(layer "F.SilkS")
		)
		(fp_line
			(start 1.1049 -0.724916)
			(end -1.1049 -0.724916)
			(stroke
				(width 0.1)
				(type default)
			)
			(layer "F.Fab")
		)
		(fp_line
			(start -1.1049 -0.724916)
			(end -1.1049 0.724916)
			(stroke
				(width 0.1)
				(type default)
			)
			(layer "F.Fab")
		)
		(fp_line
			(start 1.1049 0.724916)
			(end 1.1049 -0.724916)
			(stroke
				(width 0.1)
				(type default)
			)
			(layer "F.Fab")
		)
		(fp_line
			(start -1.1049 0.724916)
			(end 1.1049 0.724916)
			(stroke
				(width 0.1)
				(type default)
			)
			(layer "F.Fab")
		)
		(pad "1" smd rect
			(at -0.889 0 270)
			(size 1.016 1.27)
			(layers "F.Cu" "F.Mask" "F.Paste")
			(net "P12V_SSD5_R")
		)
		(pad "2" smd rect
			(at 0.889 0 270)
			(size 1.016 1.27)
			(layers "F.Cu" "F.Mask" "F.Paste")
			(net "GND")
		)
	)
	(footprint ""
		(layer "F.Cu")
		(at 238.124746 -113.777268 180)
		(property "Reference" "R950"
			(at 0 0 180)
			(layer "F.SilkS")
			(hide yes)
			(effects
				(font
					(size 1.27 1.27)
				)
			)
		)
		(property "Value" ""
			(at 0 0 180)
			(layer "F.Fab")
			(effects
				(font
					(size 1.27 1.27)
				)
			)
		)
		(duplicate_pad_numbers_are_jumpers no)
		(fp_line
			(start 0.7874 0.4064)
			(end -0.7874 0.4064)
			(stroke
				(width 0.1524)
				(type default)
			)
			(layer "F.SilkS")
		)
		(fp_line
			(start 0.7874 -0.4064)
			(end 0.7874 0.4064)
			(stroke
				(width 0.1524)
				(type default)
			)
			(layer "F.SilkS")
		)
		(fp_line
			(start -0.7874 0.4064)
			(end -0.7874 -0.4064)
			(stroke
				(width 0.1524)
				(type default)
			)
			(layer "F.SilkS")
		)
		(fp_line
			(start -0.7874 -0.4064)
			(end 0.7874 -0.4064)
			(stroke
				(width 0.1524)
				(type default)
			)
			(layer "F.SilkS")
		)
		(fp_line
			(start 0.67945 0.3048)
			(end 0.120396 0.3048)
			(stroke
				(width 0.1)
				(type default)
			)
			(layer "F.Fab")
		)
		(fp_line
			(start 0.67945 -0.3048)
			(end 0.67945 0.3048)
			(stroke
				(width 0.1)
				(type default)
			)
			(layer "F.Fab")
		)
		(fp_line
			(start 0.12065 -0.2794)
			(end 0.12065 -0.3048)
			(stroke
				(width 0.1)
				(type default)
			)
			(layer "F.Fab")
		)
		(fp_line
			(start 0.12065 -0.3048)
			(end 0.67945 -0.3048)
			(stroke
				(width 0.1)
				(type default)
			)
			(layer "F.Fab")
		)
		(fp_line
			(start 0.120396 0.3048)
			(end 0.120396 0.2794)
			(stroke
				(width 0.1)
				(type default)
			)
			(layer "F.Fab")
		)
		(fp_line
			(start 0.120396 0.2794)
			(end -0.12065 0.2794)
			(stroke
				(width 0.1)
				(type default)
			)
			(layer "F.Fab")
		)
		(fp_line
			(start -0.12065 0.3048)
			(end -0.67945 0.3048)
			(stroke
				(width 0.1)
				(type default)
			)
			(layer "F.Fab")
		)
		(fp_line
			(start -0.12065 0.2794)
			(end -0.12065 0.3048)
			(stroke
				(width 0.1)
				(type default)
			)
			(layer "F.Fab")
		)
		(fp_line
			(start -0.12065 -0.2794)
			(end 0.12065 -0.2794)
			(stroke
				(width 0.1)
				(type default)
			)
			(layer "F.Fab")
		)
		(fp_line
			(start -0.12065 -0.305054)
			(end -0.12065 -0.2794)
			(stroke
				(width 0.1)
				(type default)
			)
			(layer "F.Fab")
		)
		(fp_line
			(start -0.67945 0.3048)
			(end -0.67945 -0.305054)
			(stroke
				(width 0.1)
				(type default)
			)
			(layer "F.Fab")
		)
		(fp_line
			(start -0.67945 -0.305054)
			(end -0.12065 -0.305054)
			(stroke
				(width 0.1)
				(type default)
			)
			(layer "F.Fab")
		)
		(pad "1" smd circle
			(at -0.40005 0 180)
			(size 0 0)
			(layers "F.Cu" "F.Mask" "F.Paste")
			(net "GND")
		)
		(pad "2" smd circle
			(at 0.40005 0 180)
			(size 0 0)
			(layers "F.Cu" "F.Mask" "F.Paste")
			(net "P12V_NIC3_CO_EN")
		)
	)
)
